(kicad_pcb
	(version 20241229)
	(generator "pcbnew")
	(generator_version "9.0")
	(general
		(thickness 1.711)
		(legacy_teardrops no)
	)
	(paper "A4")
	(title_block
		(title "Antmicro Baseboard for Jetson AGX Thor")
		(date "2026-02-18")
		(rev "1.1.0")
		(company "Antmicro Ltd")
		(comment 1 "www.antmicro.com")
		(comment 9 "footprints 145-145 of 1170")
	)
	(layers
		(0 "F.Cu" signal)
		(4 "In1.Cu" signal)
		(6 "In2.Cu" signal)
		(8 "In3.Cu" signal)
		(10 "In4.Cu" jumper)
		(12 "In5.Cu" signal)
		(14 "In6.Cu" signal)
		(16 "In7.Cu" signal)
		(18 "In8.Cu" signal)
		(2 "B.Cu" signal)
		(9 "F.Adhes" user "F.Adhesive")
		(11 "B.Adhes" user "B.Adhesive")
		(13 "F.Paste" user)
		(15 "B.Paste" user)
		(5 "F.SilkS" user "F.Silkscreen")
		(7 "B.SilkS" user "B.Silkscreen")
		(1 "F.Mask" user)
		(3 "B.Mask" user)
		(17 "Dwgs.User" user "User.Drawings")
		(19 "Cmts.User" user "User.Comments")
		(21 "Eco1.User" user "User.Eco1")
		(23 "Eco2.User" user "User.Eco2")
		(25 "Edge.Cuts" user)
		(27 "Margin" user)
		(31 "F.CrtYd" user "F.Courtyard")
		(29 "B.CrtYd" user "B.Courtyard")
		(35 "F.Fab" user)
		(33 "B.Fab" user)
	)
	(footprint "antmicro-footprints:WQFN-40_1EP_6x3mm_Pitch0.4mm_EP4.7x2.7mm"
		(layer "F.Cu")
		(at 214.463632 89.772856 -90)
		(property "Reference" "U33"
			(at -3.500856 2.663632 180)
			(layer "F.SilkS")
			(effects
				(font
					(size 0.7 0.7)
					(thickness 0.15)
				)
				(justify right top)
			)
		)
		(property "Value" "TUSB1046-DCIRNQ"
			(at 0 3.4 270)
			(unlocked yes)
			(layer "F.Fab")
			(effects
				(font
					(size 0.7 0.7)
					(thickness 0.15)
				)
				(justify left bottom)
			)
		)
		(property "Datasheet" "https://www.ti.com/lit/ds/sllsew2d/sllsew2d.pdf?ts=1662107117482&ref_url=https%253A%252F%252Fwww.google.com%252F"
			(at 0 0 90)
			(layer "F.Fab")
			(hide yes)
			(effects
				(font
					(size 1.27 1.27)
					(thickness 0.15)
				)
			)
		)
		(property "Description" "Analog & Digital Crosspoint ICs USB Type-C DP ALT Mode, 10-Gbps linear redriver crosspoint switch 40-WQFN 0°C to 70°C"
			(at 0 0 90)
			(layer "F.Fab")
			(hide yes)
			(effects
				(font
					(size 1.27 1.27)
					(thickness 0.15)
				)
			)
		)
		(property "MPN" "TUSB1046-DCIRNQT"
			(at 0 0 270)
			(unlocked yes)
			(layer "F.Fab")
			(hide yes)
			(effects
				(font
					(size 1 1)
					(thickness 0.15)
				)
			)
		)
		(property "Manufacturer" "Texas Instruments"
			(at 0 0 270)
			(unlocked yes)
			(layer "F.Fab")
			(hide yes)
			(effects
				(font
					(size 1 1)
					(thickness 0.15)
				)
			)
		)
		(property "Author" "Antmicro"
			(at 0 0 270)
			(unlocked yes)
			(layer "F.Fab")
			(hide yes)
			(effects
				(font
					(size 1 1)
					(thickness 0.15)
				)
			)
		)
		(property "License" "Apache-2.0"
			(at 0 0 270)
			(unlocked yes)
			(layer "F.Fab")
			(hide yes)
			(effects
				(font
					(size 1 1)
					(thickness 0.15)
				)
			)
		)
		(sheetname "/USB DP Alt mode/")
		(sheetfile "usb_dp.kicad_sch")
		(attr smd)
		(fp_line
			(start -3.101 2.1)
			(end -3.101 1.6)
			(stroke
				(width 0.15)
				(type solid)
			)
			(layer "F.SilkS")
		)
		(fp_line
			(start -2.4 2.1)
			(end -3.101 2.1)
			(stroke
				(width 0.15)
				(type solid)
			)
			(layer "F.SilkS")
		)
		(fp_line
			(start 3.1 2.1)
			(end 2.398 2.1)
			(stroke
				(width 0.15)
				(type solid)
			)
			(layer "F.SilkS")
		)
		(fp_line
			(start 3.1 1.6)
			(end 3.1 2.1)
			(stroke
				(width 0.15)
				(type solid)
			)
			(layer "F.SilkS")
		)
		(fp_line
			(start -2.4 -2.101)
			(end -3.101 -2.101)
			(stroke
				(width 0.15)
				(type solid)
			)
			(layer "F.SilkS")
		)
		(fp_line
			(start 3.1 -2.101)
			(end 3.1 -1.601)
			(stroke
				(width 0.15)
				(type solid)
			)
			(layer "F.SilkS")
		)
		(fp_line
			(start 3.1 -2.101)
			(end 2.398 -2.101)
			(stroke
				(width 0.15)
				(type solid)
			)
			(layer "F.SilkS")
		)
		(fp_circle
			(center -3.8 -1.41)
			(end -3.75 -1.36)
			(stroke
				(width 0.15)
				(type solid)
			)
			(fill yes)
			(layer "F.SilkS")
		)
		(fp_rect
			(start -3.5 -2.5)
			(end 3.499 2.499)
			(stroke
				(width 0.05)
				(type solid)
			)
			(fill no)
			(layer "F.CrtYd")
		)
		(fp_line
			(start -2.9 1.898)
			(end -2.9 -1.2)
			(stroke
				(width 0.15)
				(type solid)
			)
			(layer "F.Fab")
		)
		(fp_line
			(start 2.898 1.898)
			(end -2.9 1.898)
			(stroke
				(width 0.15)
				(type solid)
			)
			(layer "F.Fab")
		)
		(fp_line
			(start -2.9 -1.2)
			(end -2.2 -1.9)
			(stroke
				(width 0.15)
				(type solid)
			)
			(layer "F.Fab")
		)
		(fp_line
			(start -2.2 -1.9)
			(end 2.898 -1.901)
			(stroke
				(width 0.15)
				(type solid)
			)
			(layer "F.Fab")
		)
		(fp_line
			(start 2.898 -1.901)
			(end 2.898 1.898)
			(stroke
				(width 0.15)
				(type solid)
			)
			(layer "F.Fab")
		)
		(fp_text user "${REFERENCE}"
			(at -3.101 4.099 90)
			(layer "F.Fab")
			(effects
				(font
					(size 0.7 0.7)
					(thickness 0.15)
				)
				(justify right top)
			)
		)
		(fp_text user "License: Apache-2.0"
			(at -3.101 6.099 90)
			(layer "F.Fab")
			(effects
				(font
					(size 0.7 0.7)
					(thickness 0.15)
				)
				(justify right top)
			)
		)
		(fp_text user "Author: Antmicro"
			(at -3.101 5.099 90)
			(layer "F.Fab")
			(effects
				(font
					(size 0.7 0.7)
					(thickness 0.15)
				)
				(justify right top)
			)
		)
		(pad "1" smd roundrect
			(at -2.9 -1.401)
			(size 0.2 0.6)
			(layers "F.Cu" "F.Mask" "F.Paste")
			(roundrect_rratio 0.25)
			(net 2 "+3V3")
			(pinfunction "VCC")
			(pintype "power_in")
		)
		(pad "2" smd roundrect
			(at -2.9 -1)
			(size 0.2 0.6)
			(layers "F.Cu" "F.Mask" "F.Paste")
			(roundrect_rratio 0.25)
			(net 967 "/USB DP Alt mode/USBC1_DPEQ1")
			(pinfunction "DPEQ1")
			(pintype "input")
		)
		(pad "3" smd roundrect
			(at -2.9 -0.6)
			(size 0.2 0.6)
			(layers "F.Cu" "F.Mask" "F.Paste")
			(roundrect_rratio 0.25)
			(net 965 "/USB DP Alt mode/USBC1_SSEQ1")
			(pinfunction "SSEQ1")
			(pintype "input")
		)
		(pad "4" smd roundrect
			(at -2.9 -0.202)
			(size 0.2 0.6)
			(layers "F.Cu" "F.Mask" "F.Paste")
			(roundrect_rratio 0.25)
			(net 322 "/USB DP Alt mode/USBSS1_RX_C_N")
			(pinfunction "SSRX_N")
			(pintype "output")
		)
		(pad "5" smd roundrect
			(at -2.9 0.2)
			(size 0.2 0.6)
			(layers "F.Cu" "F.Mask" "F.Paste")
			(roundrect_rratio 0.25)
			(net 302 "/USB DP Alt mode/USBSS1_RX_C_P")
			(pinfunction "SSRX_P")
			(pintype "output")
		)
		(pad "6" smd roundrect
			(at -2.9 0.598)
			(size 0.2 0.6)
			(layers "F.Cu" "F.Mask" "F.Paste")
			(roundrect_rratio 0.25)
			(net 2 "+3V3")
			(pinfunction "VCC")
			(pintype "passive")
		)
		(pad "7" smd roundrect
			(at -2.9 0.998)
			(size 0.2 0.6)
			(layers "F.Cu" "F.Mask" "F.Paste")
			(roundrect_rratio 0.25)
			(net 333 "/USB DP Alt mode/USBSS1_TX_C_N")
			(pinfunction "SSTX_N")
			(pintype "input")
		)
		(pad "8" smd roundrect
			(at -2.9 1.398)
			(size 0.2 0.6)
			(layers "F.Cu" "F.Mask" "F.Paste")
			(roundrect_rratio 0.25)
			(net 310 "/USB DP Alt mode/USBSS1_TX_C_P")
			(pinfunction "SSTX_P")
			(pintype "input")
		)
		(pad "9" smd roundrect
			(at -2.202 1.898 90)
			(size 0.2 0.6)
			(layers "F.Cu" "F.Mask" "F.Paste")
			(roundrect_rratio 0.25)
			(net 583 "/SoM_IO2/DP0.TX0+")
			(pinfunction "DP0_P")
			(pintype "input")
		)
		(pad "10" smd roundrect
			(at -1.801 1.898 90)
			(size 0.2 0.6)
			(layers "F.Cu" "F.Mask" "F.Paste")
			(roundrect_rratio 0.25)
			(net 663 "/SoM_IO2/DP0.TX0-")
			(pinfunction "DP0_N")
			(pintype "input")
		)
		(pad "11" smd roundrect
			(at -1.401 1.898 90)
			(size 0.2 0.6)
			(layers "F.Cu" "F.Mask" "F.Paste")
			(roundrect_rratio 0.25)
			(net 964 "/USB DP Alt mode/USBC1_SSEQ0")
			(pinfunction "SSEQ0/A0")
			(pintype "input")
		)
		(pad "12" smd roundrect
			(at -1 1.898 90)
			(size 0.2 0.6)
			(layers "F.Cu" "F.Mask" "F.Paste")
			(roundrect_rratio 0.25)
			(net 612 "/SoM_IO2/DP0.TX1+")
			(pinfunction "DP1_P")
			(pintype "input")
		)
		(pad "13" smd roundrect
			(at -0.6 1.898 90)
			(size 0.2 0.6)
			(layers "F.Cu" "F.Mask" "F.Paste")
			(roundrect_rratio 0.25)
			(net 792 "/SoM_IO2/DP0.TX1-")
			(pinfunction "DP1_N")
			(pintype "input")
		)
		(pad "14" smd roundrect
			(at -0.202 1.898 90)
			(size 0.2 0.6)
			(layers "F.Cu" "F.Mask" "F.Paste")
			(roundrect_rratio 0.25)
			(net 966 "/USB DP Alt mode/USBC1_DPEQ0")
			(pinfunction "DPEQ0/A1")
			(pintype "input")
		)
		(pad "15" smd roundrect
			(at 0.2 1.898 90)
			(size 0.2 0.6)
			(layers "F.Cu" "F.Mask" "F.Paste")
			(roundrect_rratio 0.25)
			(net 786 "/SoM_IO2/DP0.TX2+")
			(pinfunction "DP2_P")
			(pintype "input")
		)
		(pad "16" smd roundrect
			(at 0.598 1.898 90)
			(size 0.2 0.6)
			(layers "F.Cu" "F.Mask" "F.Paste")
			(roundrect_rratio 0.25)
			(net 666 "/SoM_IO2/DP0.TX2-")
			(pinfunction "DP2_N")
			(pintype "input")
		)
		(pad "17" smd roundrect
			(at 0.998 1.898 90)
			(size 0.2 0.6)
			(layers "F.Cu" "F.Mask" "F.Paste")
			(roundrect_rratio 0.25)
			(net 963 "/USB DP Alt mode/USBC1_I2C_EN")
			(pinfunction "I2C_EN")
			(pintype "input")
		)
		(pad "18" smd roundrect
			(at 1.398 1.898 90)
			(size 0.2 0.6)
			(layers "F.Cu" "F.Mask" "F.Paste")
			(roundrect_rratio 0.25)
			(net 557 "/SoM_IO2/DP0.TX3+")
			(pinfunction "DP3_P")
			(pintype "input")
		)
		(pad "19" smd roundrect
			(at 1.8 1.898 90)
			(size 0.2 0.6)
			(layers "F.Cu" "F.Mask" "F.Paste")
			(roundrect_rratio 0.25)
			(net 553 "/SoM_IO2/DP0.TX3-")
			(pinfunction "DP3_N")
			(pintype "input")
		)
		(pad "20" smd roundrect
			(at 2.2 1.898 90)
			(size 0.2 0.6)
			(layers "F.Cu" "F.Mask" "F.Paste")
			(roundrect_rratio 0.25)
			(net 2 "+3V3")
			(pinfunction "VCC")
			(pintype "passive")
		)
		(pad "21" smd roundrect
			(at 2.898 1.398 180)
			(size 0.2 0.6)
			(layers "F.Cu" "F.Mask" "F.Paste")
			(roundrect_rratio 0.25)
			(net 942 "/USB DP Alt mode/USBC1_FLIP")
			(pinfunction "FLIP/SCL")
			(pintype "input")
		)
		(pad "22" smd roundrect
			(at 2.898 0.998 180)
			(size 0.2 0.6)
			(layers "F.Cu" "F.Mask" "F.Paste")
			(roundrect_rratio 0.25)
			(net 943 "/USB DP Alt mode/USBC1_CTL0")
			(pinfunction "CTL0/SDA")
			(pintype "input")
		)
		(pad "23" smd roundrect
			(at 2.898 0.598 180)
			(size 0.2 0.6)
			(layers "F.Cu" "F.Mask" "F.Paste")
			(roundrect_rratio 0.25)
			(net 944 "/USB DP Alt mode/USBC1_CTL1")
			(pinfunction "CTL1/HPDIN")
			(pintype "input")
		)
		(pad "24" smd roundrect
			(at 2.898 0.2 180)
			(size 0.2 0.6)
			(layers "F.Cu" "F.Mask" "F.Paste")
			(roundrect_rratio 0.25)
			(net 635 "/SoM_IO2/DP0.AUX+")
			(pinfunction "AUX_P")
			(pintype "bidirectional")
		)
		(pad "25" smd roundrect
			(at 2.898 -0.202 180)
			(size 0.2 0.6)
			(layers "F.Cu" "F.Mask" "F.Paste")
			(roundrect_rratio 0.25)
			(net 607 "/SoM_IO2/DP0.AUX-")
			(pinfunction "AUX_N")
			(pintype "bidirectional")
		)
		(pad "26" smd roundrect
			(at 2.898 -0.6 180)
			(size 0.2 0.6)
			(layers "F.Cu" "F.Mask" "F.Paste")
			(roundrect_rratio 0.25)
			(net 815 "/USB DP Alt mode/USBC1_SBU_P")
			(pinfunction "SBU2")
			(pintype "bidirectional")
		)
		(pad "27" smd roundrect
			(at 2.898 -1 180)
			(size 0.2 0.6)
			(layers "F.Cu" "F.Mask" "F.Paste")
			(roundrect_rratio 0.25)
			(net 821 "/USB DP Alt mode/USBC1_SBU_N")
			(pinfunction "SBU1")
			(pintype "bidirectional")
		)
		(pad "28" smd roundrect
			(at 2.898 -1.401 180)
			(size 0.2 0.6)
			(layers "F.Cu" "F.Mask" "F.Paste")
			(roundrect_rratio 0.25)
			(net 2 "+3V3")
			(pinfunction "VCC")
			(pintype "passive")
		)
		(pad "29" smd roundrect
			(at 2.2 -1.901 270)
			(size 0.2 0.6)
			(layers "F.Cu" "F.Mask" "F.Paste")
			(roundrect_rratio 0.25)
			(net 1044 "Net-(U33-CAD_SNK{slash}RSVD1)")
			(pinfunction "CAD_SNK/RSVD1")
			(pintype "bidirectional")
		)
		(pad "30" smd roundrect
			(at 1.8 -1.901 270)
			(size 0.2 0.6)
			(layers "F.Cu" "F.Mask" "F.Paste")
			(roundrect_rratio 0.25)
			(net 822 "/USB DP Alt mode/USBC1_RX1_P")
			(pinfunction "RX1_P")
			(pintype "input")
		)
		(pad "31" smd roundrect
			(at 1.398 -1.901 270)
			(size 0.2 0.6)
			(layers "F.Cu" "F.Mask" "F.Paste")
			(roundrect_rratio 0.25)
			(net 819 "/USB DP Alt mode/USBC1_RX1_N")
			(pinfunction "RX1_N")
			(pintype "input")
		)
		(pad "32" smd roundrect
			(at 0.998 -1.901 270)
			(size 0.2 0.6)
			(layers "F.Cu" "F.Mask" "F.Paste")
			(roundrect_rratio 0.25)
			(net 957 "/USB DP Alt mode/HPDIN")
			(pinfunction "HPDIN/RSVD2")
			(pintype "bidirectional")
		)
		(pad "33" smd roundrect
			(at 0.598 -1.901 270)
			(size 0.2 0.6)
			(layers "F.Cu" "F.Mask" "F.Paste")
			(roundrect_rratio 0.25)
			(net 344 "/USB DP Alt mode/USBC1_TX1_P")
			(pinfunction "TX1_P")
			(pintype "output")
		)
		(pad "34" smd roundrect
			(at 0.2 -1.901 270)
			(size 0.2 0.6)
			(layers "F.Cu" "F.Mask" "F.Paste")
			(roundrect_rratio 0.25)
			(net 370 "/USB DP Alt mode/USBC1_TX1_N")
			(pinfunction "TX1_N")
			(pintype "output")
		)
		(pad "35" smd roundrect
			(at -0.202 -1.901 270)
			(size 0.2 0.6)
			(layers "F.Cu" "F.Mask" "F.Paste")
			(roundrect_rratio 0.25)
			(net 969 "/USB DP Alt mode/USBC1_EQ1")
			(pinfunction "EQ1")
			(pintype "input")
		)
		(pad "36" smd roundrect
			(at -0.6 -1.901 270)
			(size 0.2 0.6)
			(layers "F.Cu" "F.Mask" "F.Paste")
			(roundrect_rratio 0.25)
			(net 372 "/USB DP Alt mode/USBC1_TX2_N")
			(pinfunction "TX2_N")
			(pintype "output")
		)
		(pad "37" smd roundrect
			(at -1 -1.901 270)
			(size 0.2 0.6)
			(layers "F.Cu" "F.Mask" "F.Paste")
			(roundrect_rratio 0.25)
			(net 354 "/USB DP Alt mode/USBC1_TX2_P")
			(pinfunction "TX2_P")
			(pintype "output")
		)
		(pad "38" smd roundrect
			(at -1.401 -1.901 270)
			(size 0.2 0.6)
			(layers "F.Cu" "F.Mask" "F.Paste")
			(roundrect_rratio 0.25)
			(net 968 "/USB DP Alt mode/USBC1_EQ0")
			(pinfunction "EQ0")
			(pintype "input")
		)
		(pad "39" smd roundrect
			(at -1.801 -1.901 270)
			(size 0.2 0.6)
			(layers "F.Cu" "F.Mask" "F.Paste")
			(roundrect_rratio 0.25)
			(net 820 "/USB DP Alt mode/USBC1_RX2_N")
			(pinfunction "RX2_N")
			(pintype "input")
		)
		(pad "40" smd roundrect
			(at -2.202 -1.901 270)
			(size 0.2 0.6)
			(layers "F.Cu" "F.Mask" "F.Paste")
			(roundrect_rratio 0.25)
			(net 818 "/USB DP Alt mode/USBC1_RX2_P")
			(pinfunction "RX2_P")
			(pintype "input")
		)
		(pad "41" smd roundrect
			(at -1.5 -0.652 90)
			(size 1 0.8)
			(layers "F.Cu" "F.Mask" "F.Paste")
			(roundrect_rratio 0.05)
			(net 1 "GND")
			(pinfunction "GND")
			(pintype "power_in")
		)
		(pad "41" smd roundrect
			(at -1.5 0.748 90)
			(size 1 0.8)
			(layers "F.Cu" "F.Mask" "F.Paste")
			(roundrect_rratio 0.05)
			(net 1 "GND")
			(pinfunction "GND")
			(pintype "power_in")
		)
		(pad "41" smd roundrect
			(at 0 0 90)
			(size 4.7 2.7)
			(layers "F.Cu" "F.Mask")
			(roundrect_rratio 0.01851851852)
			(net 1 "GND")
			(pinfunction "GND")
			(pintype "power_in")
		)
		(pad "41" smd roundrect
			(at 0.05 -0.652 90)
			(size 1 0.8)
			(layers "F.Cu" "F.Mask" "F.Paste")
			(roundrect_rratio 0.05)
			(net 1 "GND")
			(pinfunction "GND")
			(pintype "power_in")
		)
		(pad "41" smd roundrect
			(at 0.05 0.748 90)
			(size 1 0.8)
			(layers "F.Cu" "F.Mask" "F.Paste")
			(roundrect_rratio 0.05)
			(net 1 "GND")
			(pinfunction "GND")
			(pintype "power_in")
		)
		(pad "41" smd roundrect
			(at 1.499 -0.652 90)
			(size 1 0.8)
			(layers "F.Cu" "F.Mask" "F.Paste")
			(roundrect_rratio 0.05)
			(net 1 "GND")
			(pinfunction "GND")
			(pintype "power_in")
		)
		(pad "41" smd roundrect
			(at 1.499 0.748 90)
			(size 1 0.8)
			(layers "F.Cu" "F.Mask" "F.Paste")
			(roundrect_rratio 0.05)
			(net 1 "GND")
			(pinfunction "GND")
			(pintype "power_in")
		)
	)
)
